(kicad_pcb
	(version 20260206)
	(generator "pcbnew")
	(generator_version "10.0")
	(general
		(thickness 1.6)
		(legacy_teardrops no)
	)
	(paper "A4")
	(title_block
		(title "01162023_DA0F0TEBIF0_F0T_Expander_BD_F_brd_V02_OCP.brd")
		(comment 1 "Grand Teton / footprints 1118-1123 of 9728")
	)
	(layers
		(0 "F.Cu" signal "TOP")
		(4 "In1.Cu" signal "GND")
		(6 "In2.Cu" signal "VCC")
		(8 "In3.Cu" signal "VCC1")
		(10 "In4.Cu" signal "GND1")
		(12 "In5.Cu" signal "IN1")
		(14 "In6.Cu" signal "GND2")
		(16 "In7.Cu" signal "IN2")
		(18 "In8.Cu" signal "GND3")
		(20 "In9.Cu" signal "IN3")
		(22 "In10.Cu" signal "GND4")
		(24 "In11.Cu" signal "IN4")
		(26 "In12.Cu" signal "GND5")
		(28 "In13.Cu" signal "IN5")
		(30 "In14.Cu" signal "GND6")
		(32 "In15.Cu" signal "IN6")
		(34 "In16.Cu" signal "GND7")
		(2 "B.Cu" signal "BOTTOM")
		(9 "F.Adhes" user "F.Adhesive")
		(11 "B.Adhes" user "B.Adhesive")
		(13 "F.Paste" user "Package Geometry/Pastemask Top")
		(15 "B.Paste" user "Package Geometry/Pastemask Bottom")
		(5 "F.SilkS" user "Ref Des/Silkscreen Top")
		(7 "B.SilkS" user "Ref Des/Silkscreen Bottom")
		(1 "F.Mask" user "Board Geometry/Soldermask Top")
		(3 "B.Mask" user "Board Geometry/Soldermask Bottom")
		(17 "Dwgs.User" user "User.Drawings")
		(19 "Cmts.User" user "User.Comments")
		(21 "Eco1.User" user "User.Eco1")
		(23 "Eco2.User" user "User.Eco2")
		(25 "Edge.Cuts" user "Board Geometry/Outline")
		(27 "Margin" user)
		(31 "F.CrtYd" user "Package Geometry/Place Bound Top")
		(29 "B.CrtYd" user "Package Geometry/Place Bound Bottom")
		(35 "F.Fab" user "Ref Des/Assembly Top")
		(33 "B.Fab" user "Ref Des/Assembly Bottom")
	)
	(footprint ""
		(layer "F.Cu")
		(at 234.493816 -372.8974)
		(property "Reference" "PR39"
			(at 0 0 0)
			(layer "F.SilkS")
			(hide yes)
			(effects
				(font
					(size 1.27 1.27)
				)
			)
		)
		(property "Value" ""
			(at 0 0 0)
			(layer "F.Fab")
			(effects
				(font
					(size 1.27 1.27)
				)
			)
		)
		(duplicate_pad_numbers_are_jumpers no)
		(fp_line
			(start -0.7874 -0.4064)
			(end 0.7874 -0.4064)
			(stroke
				(width 0.1524)
				(type default)
			)
			(layer "F.SilkS")
		)
		(fp_line
			(start -0.7874 0.4064)
			(end -0.7874 -0.4064)
			(stroke
				(width 0.1524)
				(type default)
			)
			(layer "F.SilkS")
		)
		(fp_line
			(start 0.7874 -0.4064)
			(end 0.7874 0.4064)
			(stroke
				(width 0.1524)
				(type default)
			)
			(layer "F.SilkS")
		)
		(fp_line
			(start 0.7874 0.4064)
			(end -0.7874 0.4064)
			(stroke
				(width 0.1524)
				(type default)
			)
			(layer "F.SilkS")
		)
		(fp_line
			(start -0.67945 -0.305054)
			(end -0.12065 -0.305054)
			(stroke
				(width 0.1)
				(type default)
			)
			(layer "F.Fab")
		)
		(fp_line
			(start -0.67945 0.3048)
			(end -0.67945 -0.305054)
			(stroke
				(width 0.1)
				(type default)
			)
			(layer "F.Fab")
		)
		(fp_line
			(start -0.12065 -0.305054)
			(end -0.12065 -0.2794)
			(stroke
				(width 0.1)
				(type default)
			)
			(layer "F.Fab")
		)
		(fp_line
			(start -0.12065 -0.2794)
			(end 0.12065 -0.2794)
			(stroke
				(width 0.1)
				(type default)
			)
			(layer "F.Fab")
		)
		(fp_line
			(start -0.12065 0.2794)
			(end -0.12065 0.3048)
			(stroke
				(width 0.1)
				(type default)
			)
			(layer "F.Fab")
		)
		(fp_line
			(start -0.12065 0.3048)
			(end -0.67945 0.3048)
			(stroke
				(width 0.1)
				(type default)
			)
			(layer "F.Fab")
		)
		(fp_line
			(start 0.120396 0.2794)
			(end -0.12065 0.2794)
			(stroke
				(width 0.1)
				(type default)
			)
			(layer "F.Fab")
		)
		(fp_line
			(start 0.120396 0.3048)
			(end 0.120396 0.2794)
			(stroke
				(width 0.1)
				(type default)
			)
			(layer "F.Fab")
		)
		(fp_line
			(start 0.12065 -0.3048)
			(end 0.67945 -0.3048)
			(stroke
				(width 0.1)
				(type default)
			)
			(layer "F.Fab")
		)
		(fp_line
			(start 0.12065 -0.2794)
			(end 0.12065 -0.3048)
			(stroke
				(width 0.1)
				(type default)
			)
			(layer "F.Fab")
		)
		(fp_line
			(start 0.67945 -0.3048)
			(end 0.67945 0.3048)
			(stroke
				(width 0.1)
				(type default)
			)
			(layer "F.Fab")
		)
		(fp_line
			(start 0.67945 0.3048)
			(end 0.120396 0.3048)
			(stroke
				(width 0.1)
				(type default)
			)
			(layer "F.Fab")
		)
		(pad "1" smd circle
			(at -0.40005 0)
			(size 0 0)
			(layers "F.Cu" "F.Mask" "F.Paste")
			(net "HSC_FLT_TYPE_2")
		)
		(pad "2" smd circle
			(at 0.40005 0)
			(size 0 0)
			(layers "F.Cu" "F.Mask" "F.Paste")
			(net "HSC_FLT_TYPE_R")
		)
	)
	(footprint ""
		(layer "F.Cu")
		(at 207.479392 -300.641004 -90)
		(property "Reference" "R3927"
			(at 0 0 270)
			(layer "F.SilkS")
			(hide yes)
			(effects
				(font
					(size 1.27 1.27)
				)
			)
		)
		(property "Value" ""
			(at 0 0 270)
			(layer "F.Fab")
			(effects
				(font
					(size 1.27 1.27)
				)
			)
		)
		(duplicate_pad_numbers_are_jumpers no)
		(fp_line
			(start -0.7874 0.4064)
			(end -0.7874 -0.4064)
			(stroke
				(width 0.1524)
				(type default)
			)
			(layer "F.SilkS")
		)
		(fp_line
			(start 0.7874 0.4064)
			(end -0.7874 0.4064)
			(stroke
				(width 0.1524)
				(type default)
			)
			(layer "F.SilkS")
		)
		(fp_line
			(start -0.7874 -0.4064)
			(end 0.7874 -0.4064)
			(stroke
				(width 0.1524)
				(type default)
			)
			(layer "F.SilkS")
		)
		(fp_line
			(start 0.7874 -0.4064)
			(end 0.7874 0.4064)
			(stroke
				(width 0.1524)
				(type default)
			)
			(layer "F.SilkS")
		)
		(fp_line
			(start -0.67945 0.3048)
			(end -0.67945 -0.305054)
			(stroke
				(width 0.1)
				(type default)
			)
			(layer "F.Fab")
		)
		(fp_line
			(start -0.12065 0.3048)
			(end -0.67945 0.3048)
			(stroke
				(width 0.1)
				(type default)
			)
			(layer "F.Fab")
		)
		(fp_line
			(start 0.120396 0.3048)
			(end 0.120396 0.2794)
			(stroke
				(width 0.1)
				(type default)
			)
			(layer "F.Fab")
		)
		(fp_line
			(start 0.67945 0.3048)
			(end 0.120396 0.3048)
			(stroke
				(width 0.1)
				(type default)
			)
			(layer "F.Fab")
		)
		(fp_line
			(start -0.12065 0.2794)
			(end -0.12065 0.3048)
			(stroke
				(width 0.1)
				(type default)
			)
			(layer "F.Fab")
		)
		(fp_line
			(start 0.120396 0.2794)
			(end -0.12065 0.2794)
			(stroke
				(width 0.1)
				(type default)
			)
			(layer "F.Fab")
		)
		(fp_line
			(start -0.12065 -0.2794)
			(end 0.12065 -0.2794)
			(stroke
				(width 0.1)
				(type default)
			)
			(layer "F.Fab")
		)
		(fp_line
			(start 0.12065 -0.2794)
			(end 0.12065 -0.3048)
			(stroke
				(width 0.1)
				(type default)
			)
			(layer "F.Fab")
		)
		(fp_line
			(start 0.12065 -0.3048)
			(end 0.67945 -0.3048)
			(stroke
				(width 0.1)
				(type default)
			)
			(layer "F.Fab")
		)
		(fp_line
			(start 0.67945 -0.3048)
			(end 0.67945 0.3048)
			(stroke
				(width 0.1)
				(type default)
			)
			(layer "F.Fab")
		)
		(fp_line
			(start -0.67945 -0.305054)
			(end -0.12065 -0.305054)
			(stroke
				(width 0.1)
				(type default)
			)
			(layer "F.Fab")
		)
		(fp_line
			(start -0.12065 -0.305054)
			(end -0.12065 -0.2794)
			(stroke
				(width 0.1)
				(type default)
			)
			(layer "F.Fab")
		)
		(pad "1" smd circle
			(at -0.40005 0 270)
			(size 0 0)
			(layers "F.Cu" "F.Mask" "F.Paste")
			(net "I2C0_PEX1_SCL")
		)
		(pad "2" smd circle
			(at 0.40005 0 270)
			(size 0 0)
			(layers "F.Cu" "F.Mask" "F.Paste")
			(net "I2C_PEX1_HOST_SCL")
		)
	)
	(footprint ""
		(layer "F.Cu")
		(at 106.596942 -115.646454 180)
		(property "Reference" "PR6874"
			(at 0 0 180)
			(layer "F.SilkS")
			(hide yes)
			(effects
				(font
					(size 1.27 1.27)
				)
			)
		)
		(property "Value" ""
			(at 0 0 180)
			(layer "F.Fab")
			(effects
				(font
					(size 1.27 1.27)
				)
			)
		)
		(duplicate_pad_numbers_are_jumpers no)
		(fp_line
			(start 0.7874 0.4064)
			(end -0.7874 0.4064)
			(stroke
				(width 0.1524)
				(type default)
			)
			(layer "F.SilkS")
		)
		(fp_line
			(start 0.7874 -0.4064)
			(end 0.7874 0.4064)
			(stroke
				(width 0.1524)
				(type default)
			)
			(layer "F.SilkS")
		)
		(fp_line
			(start -0.7874 0.4064)
			(end -0.7874 -0.4064)
			(stroke
				(width 0.1524)
				(type default)
			)
			(layer "F.SilkS")
		)
		(fp_line
			(start -0.7874 -0.4064)
			(end 0.7874 -0.4064)
			(stroke
				(width 0.1524)
				(type default)
			)
			(layer "F.SilkS")
		)
		(fp_line
			(start 0.67945 0.3048)
			(end 0.120396 0.3048)
			(stroke
				(width 0.1)
				(type default)
			)
			(layer "F.Fab")
		)
		(fp_line
			(start 0.67945 -0.3048)
			(end 0.67945 0.3048)
			(stroke
				(width 0.1)
				(type default)
			)
			(layer "F.Fab")
		)
		(fp_line
			(start 0.12065 -0.2794)
			(end 0.12065 -0.3048)
			(stroke
				(width 0.1)
				(type default)
			)
			(layer "F.Fab")
		)
		(fp_line
			(start 0.12065 -0.3048)
			(end 0.67945 -0.3048)
			(stroke
				(width 0.1)
				(type default)
			)
			(layer "F.Fab")
		)
		(fp_line
			(start 0.120396 0.3048)
			(end 0.120396 0.2794)
			(stroke
				(width 0.1)
				(type default)
			)
			(layer "F.Fab")
		)
		(fp_line
			(start 0.120396 0.2794)
			(end -0.12065 0.2794)
			(stroke
				(width 0.1)
				(type default)
			)
			(layer "F.Fab")
		)
		(fp_line
			(start -0.12065 0.3048)
			(end -0.67945 0.3048)
			(stroke
				(width 0.1)
				(type default)
			)
			(layer "F.Fab")
		)
		(fp_line
			(start -0.12065 0.2794)
			(end -0.12065 0.3048)
			(stroke
				(width 0.1)
				(type default)
			)
			(layer "F.Fab")
		)
		(fp_line
			(start -0.12065 -0.2794)
			(end 0.12065 -0.2794)
			(stroke
				(width 0.1)
				(type default)
			)
			(layer "F.Fab")
		)
		(fp_line
			(start -0.12065 -0.305054)
			(end -0.12065 -0.2794)
			(stroke
				(width 0.1)
				(type default)
			)
			(layer "F.Fab")
		)
		(fp_line
			(start -0.67945 0.3048)
			(end -0.67945 -0.305054)
			(stroke
				(width 0.1)
				(type default)
			)
			(layer "F.Fab")
		)
		(fp_line
			(start -0.67945 -0.305054)
			(end -0.12065 -0.305054)
			(stroke
				(width 0.1)
				(type default)
			)
			(layer "F.Fab")
		)
		(pad "1" smd circle
			(at -0.40005 0 180)
			(size 0 0)
			(layers "F.Cu" "F.Mask" "F.Paste")
			(net "P12V_NIC1_CO_OV_FB")
		)
		(pad "2" smd circle
			(at 0.40005 0 180)
			(size 0 0)
			(layers "F.Cu" "F.Mask" "F.Paste")
			(net "GND")
		)
	)
	(footprint ""
		(layer "F.Cu")
		(at 342.763094 -284.834838 90)
		(property "Reference" "PC157"
			(at 0 0 90)
			(layer "F.SilkS")
			(hide yes)
			(effects
				(font
					(size 1.27 1.27)
				)
			)
		)
		(property "Value" ""
			(at 0 0 90)
			(layer "F.Fab")
			(effects
				(font
					(size 1.27 1.27)
				)
			)
		)
		(duplicate_pad_numbers_are_jumpers no)
		(fp_line
			(start 0.7874 -0.4064)
			(end 0.7874 0.4064)
			(stroke
				(width 0.1524)
				(type default)
			)
			(layer "F.SilkS")
		)
		(fp_line
			(start -0.7874 -0.4064)
			(end 0.7874 -0.4064)
			(stroke
				(width 0.1524)
				(type default)
			)
			(layer "F.SilkS")
		)
		(fp_line
			(start 0.7874 0.4064)
			(end -0.7874 0.4064)
			(stroke
				(width 0.1524)
				(type default)
			)
			(layer "F.SilkS")
		)
		(fp_line
			(start -0.7874 0.4064)
			(end -0.7874 -0.4064)
			(stroke
				(width 0.1524)
				(type default)
			)
			(layer "F.SilkS")
		)
		(fp_line
			(start -0.12065 -0.305054)
			(end -0.12065 -0.2794)
			(stroke
				(width 0.1)
				(type default)
			)
			(layer "F.Fab")
		)
		(fp_line
			(start -0.67945 -0.305054)
			(end -0.12065 -0.305054)
			(stroke
				(width 0.1)
				(type default)
			)
			(layer "F.Fab")
		)
		(fp_line
			(start 0.67945 -0.3048)
			(end 0.67945 0.3048)
			(stroke
				(width 0.1)
				(type default)
			)
			(layer "F.Fab")
		)
		(fp_line
			(start 0.12065 -0.3048)
			(end 0.67945 -0.3048)
			(stroke
				(width 0.1)
				(type default)
			)
			(layer "F.Fab")
		)
		(fp_line
			(start 0.12065 -0.2794)
			(end 0.12065 -0.3048)
			(stroke
				(width 0.1)
				(type default)
			)
			(layer "F.Fab")
		)
		(fp_line
			(start -0.12065 -0.2794)
			(end 0.12065 -0.2794)
			(stroke
				(width 0.1)
				(type default)
			)
			(layer "F.Fab")
		)
		(fp_line
			(start 0.120396 0.2794)
			(end -0.12065 0.2794)
			(stroke
				(width 0.1)
				(type default)
			)
			(layer "F.Fab")
		)
		(fp_line
			(start -0.12065 0.2794)
			(end -0.12065 0.3048)
			(stroke
				(width 0.1)
				(type default)
			)
			(layer "F.Fab")
		)
		(fp_line
			(start 0.67945 0.3048)
			(end 0.120396 0.3048)
			(stroke
				(width 0.1)
				(type default)
			)
			(layer "F.Fab")
		)
		(fp_line
			(start 0.120396 0.3048)
			(end 0.120396 0.2794)
			(stroke
				(width 0.1)
				(type default)
			)
			(layer "F.Fab")
		)
		(fp_line
			(start -0.12065 0.3048)
			(end -0.67945 0.3048)
			(stroke
				(width 0.1)
				(type default)
			)
			(layer "F.Fab")
		)
		(fp_line
			(start -0.67945 0.3048)
			(end -0.67945 -0.305054)
			(stroke
				(width 0.1)
				(type default)
			)
			(layer "F.Fab")
		)
		(pad "1" smd circle
			(at -0.40005 0 90)
			(size 0 0)
			(layers "F.Cu" "F.Mask" "F.Paste")
			(net "SW_P12V_P0V8_PEX2_FLT")
		)
		(pad "2" smd circle
			(at 0.40005 0 90)
			(size 0 0)
			(layers "F.Cu" "F.Mask" "F.Paste")
			(net "GND")
		)
	)
	(footprint ""
		(layer "F.Cu")
		(at 344.511884 -114.960654)
		(property "Reference" "PR7038"
			(at 0 0 0)
			(layer "F.SilkS")
			(hide yes)
			(effects
				(font
					(size 1.27 1.27)
				)
			)
		)
		(property "Value" ""
			(at 0 0 0)
			(layer "F.Fab")
			(effects
				(font
					(size 1.27 1.27)
				)
			)
		)
		(duplicate_pad_numbers_are_jumpers no)
		(fp_line
			(start -0.7874 -0.4064)
			(end 0.7874 -0.4064)
			(stroke
				(width 0.1524)
				(type default)
			)
			(layer "F.SilkS")
		)
		(fp_line
			(start -0.7874 0.4064)
			(end -0.7874 -0.4064)
			(stroke
				(width 0.1524)
				(type default)
			)
			(layer "F.SilkS")
		)
		(fp_line
			(start 0.7874 -0.4064)
			(end 0.7874 0.4064)
			(stroke
				(width 0.1524)
				(type default)
			)
			(layer "F.SilkS")
		)
		(fp_line
			(start 0.7874 0.4064)
			(end -0.7874 0.4064)
			(stroke
				(width 0.1524)
				(type default)
			)
			(layer "F.SilkS")
		)
		(fp_line
			(start -0.67945 -0.305054)
			(end -0.12065 -0.305054)
			(stroke
				(width 0.1)
				(type default)
			)
			(layer "F.Fab")
		)
		(fp_line
			(start -0.67945 0.3048)
			(end -0.67945 -0.305054)
			(stroke
				(width 0.1)
				(type default)
			)
			(layer "F.Fab")
		)
		(fp_line
			(start -0.12065 -0.305054)
			(end -0.12065 -0.2794)
			(stroke
				(width 0.1)
				(type default)
			)
			(layer "F.Fab")
		)
		(fp_line
			(start -0.12065 -0.2794)
			(end 0.12065 -0.2794)
			(stroke
				(width 0.1)
				(type default)
			)
			(layer "F.Fab")
		)
		(fp_line
			(start -0.12065 0.2794)
			(end -0.12065 0.3048)
			(stroke
				(width 0.1)
				(type default)
			)
			(layer "F.Fab")
		)
		(fp_line
			(start -0.12065 0.3048)
			(end -0.67945 0.3048)
			(stroke
				(width 0.1)
				(type default)
			)
			(layer "F.Fab")
		)
		(fp_line
			(start 0.120396 0.2794)
			(end -0.12065 0.2794)
			(stroke
				(width 0.1)
				(type default)
			)
			(layer "F.Fab")
		)
		(fp_line
			(start 0.120396 0.3048)
			(end 0.120396 0.2794)
			(stroke
				(width 0.1)
				(type default)
			)
			(layer "F.Fab")
		)
		(fp_line
			(start 0.12065 -0.3048)
			(end 0.67945 -0.3048)
			(stroke
				(width 0.1)
				(type default)
			)
			(layer "F.Fab")
		)
		(fp_line
			(start 0.12065 -0.2794)
			(end 0.12065 -0.3048)
			(stroke
				(width 0.1)
				(type default)
			)
			(layer "F.Fab")
		)
		(fp_line
			(start 0.67945 -0.3048)
			(end 0.67945 0.3048)
			(stroke
				(width 0.1)
				(type default)
			)
			(layer "F.Fab")
		)
		(fp_line
			(start 0.67945 0.3048)
			(end 0.120396 0.3048)
			(stroke
				(width 0.1)
				(type default)
			)
			(layer "F.Fab")
		)
		(pad "1" smd circle
			(at -0.40005 0)
			(size 0 0)
			(layers "F.Cu" "F.Mask" "F.Paste")
			(net "P12V_NIC5_CO_IMON_VR")
		)
		(pad "2" smd circle
			(at 0.40005 0)
			(size 0 0)
			(layers "F.Cu" "F.Mask" "F.Paste")
			(net "GND")
		)
	)
	(footprint ""
		(layer "F.Cu")
		(at 247.34266 -70.844918 -90)
		(property "Reference" "PD38"
			(at 4.042918 2.23139 90)
			(unlocked yes)
			(layer "F.SilkS")
			(effects
				(font
					(size 0.7874 0.5842)
					(thickness 0.1524)
				)
				(justify left)
			)
		)
		(property "Value" ""
			(at 0 0 270)
			(layer "F.Fab")
			(effects
				(font
					(size 1.27 1.27)
				)
			)
		)
		(duplicate_pad_numbers_are_jumpers no)
		(fp_line
			(start -3.400044 1.459992)
			(end -3.400044 -1.459992)
			(stroke
				(width 0.1524)
				(type default)
			)
			(layer "F.SilkS")
		)
		(fp_line
			(start 4.107942 1.459992)
			(end -3.400044 1.459992)
			(stroke
				(width 0.1524)
				(type default)
			)
			(layer "F.SilkS")
		)
		(fp_line
			(start -3.400044 -1.459992)
			(end 4.107942 -1.459992)
			(stroke
				(width 0.1524)
				(type default)
			)
			(layer "F.SilkS")
		)
		(fp_line
			(start 4.107942 -1.459992)
			(end 4.107942 1.459992)
			(stroke
				(width 0.1524)
				(type default)
			)
			(layer "F.SilkS")
		)
		(fp_poly
			(pts
				(xy 4.107942 -1.459992) (xy 4.107942 1.459992) (xy 3.308096 1.459992) (xy 3.308096 -1.459992)
			)
			(stroke
				(width 0)
				(type default)
			)
			(fill yes)
			(layer "F.SilkS")
		)
		(fp_line
			(start -2.29997 1.459992)
			(end -2.29997 -1.459992)
			(stroke
				(width 0.1)
				(type default)
			)
			(layer "F.Fab")
		)
		(fp_line
			(start 2.29997 1.459992)
			(end -2.29997 1.459992)
			(stroke
				(width 0.1)
				(type default)
			)
			(layer "F.Fab")
		)
		(fp_line
			(start -2.29997 -1.459992)
			(end 2.29997 -1.459992)
			(stroke
				(width 0.1)
				(type default)
			)
			(layer "F.Fab")
		)
		(fp_line
			(start 2.29997 -1.459992)
			(end 2.29997 1.459992)
			(stroke
				(width 0.1)
				(type default)
			)
			(layer "F.Fab")
		)
		(fp_text user "-"
			(at 5.4102 0.29845 90)
			(unlocked yes)
			(layer "F.SilkS")
			(effects
				(font
					(size 1.905 1.4224)
					(thickness 0.1524)
				)
				(justify left)
			)
		)
		(fp_text user "+"
			(at -4.838954 -1.180592 270)
			(unlocked yes)
			(layer "F.SilkS")
			(effects
				(font
					(size 1.905 1.4224)
					(thickness 0.1524)
				)
				(justify left)
			)
		)
		(fp_text user "-"
			(at 5.4102 0.29845 90)
			(unlocked yes)
			(layer "F.Fab")
			(effects
				(font
					(size 1.905 1.4224)
					(thickness 0.1524)
				)
				(justify left)
			)
		)
		(fp_text user "+"
			(at -4.7752 -0.12065 270)
			(unlocked yes)
			(layer "F.Fab")
			(effects
				(font
					(size 1.905 1.4224)
					(thickness 0.1524)
				)
				(justify left)
			)
		)
		(pad "A" smd rect
			(at -1.999996 0)
			(size 1.7018 2.5146)
			(layers "F.Cu" "F.Mask" "F.Paste")
			(net "GND")
		)
		(pad "C" smd rect
			(at 1.999996 0)
			(size 1.7018 2.5146)
			(layers "F.Cu" "F.Mask" "F.Paste")
			(net "P12V_SSD8_R")
		)
	)
)
